(kicad_pcb
	(version 20260206)
	(generator "pcbnew")
	(generator_version "10.0")
	(general
		(thickness 1.6)
		(legacy_teardrops no)
	)
	(paper "A4")
	(title_block
		(title "01162023_DA0F0TEBIF0_F0T_Expander_BD_F_brd_V02_OCP.brd")
		(comment 1 "Grand Teton / footprints 3609-3614 of 9728")
	)
	(layers
		(0 "F.Cu" signal "TOP")
		(4 "In1.Cu" signal "GND")
		(6 "In2.Cu" signal "VCC")
		(8 "In3.Cu" signal "VCC1")
		(10 "In4.Cu" signal "GND1")
		(12 "In5.Cu" signal "IN1")
		(14 "In6.Cu" signal "GND2")
		(16 "In7.Cu" signal "IN2")
		(18 "In8.Cu" signal "GND3")
		(20 "In9.Cu" signal "IN3")
		(22 "In10.Cu" signal "GND4")
		(24 "In11.Cu" signal "IN4")
		(26 "In12.Cu" signal "GND5")
		(28 "In13.Cu" signal "IN5")
		(30 "In14.Cu" signal "GND6")
		(32 "In15.Cu" signal "IN6")
		(34 "In16.Cu" signal "GND7")
		(2 "B.Cu" signal "BOTTOM")
		(9 "F.Adhes" user "F.Adhesive")
		(11 "B.Adhes" user "B.Adhesive")
		(13 "F.Paste" user "Package Geometry/Pastemask Top")
		(15 "B.Paste" user "Package Geometry/Pastemask Bottom")
		(5 "F.SilkS" user "Ref Des/Silkscreen Top")
		(7 "B.SilkS" user "Ref Des/Silkscreen Bottom")
		(1 "F.Mask" user "Board Geometry/Soldermask Top")
		(3 "B.Mask" user "Board Geometry/Soldermask Bottom")
		(17 "Dwgs.User" user "User.Drawings")
		(19 "Cmts.User" user "User.Comments")
		(21 "Eco1.User" user "User.Eco1")
		(23 "Eco2.User" user "User.Eco2")
		(25 "Edge.Cuts" user "Board Geometry/Outline")
		(27 "Margin" user)
		(31 "F.CrtYd" user "Package Geometry/Place Bound Top")
		(29 "B.CrtYd" user "Package Geometry/Place Bound Bottom")
		(35 "F.Fab" user "Ref Des/Assembly Top")
		(33 "B.Fab" user "Ref Des/Assembly Bottom")
	)
	(footprint ""
		(layer "F.Cu")
		(at 240.200434 -250.759722 -90)
		(property "Reference" "R6244"
			(at 0 0 270)
			(layer "F.SilkS")
			(hide yes)
			(effects
				(font
					(size 1.27 1.27)
				)
			)
		)
		(property "Value" ""
			(at 0 0 270)
			(layer "F.Fab")
			(effects
				(font
					(size 1.27 1.27)
				)
			)
		)
		(duplicate_pad_numbers_are_jumpers no)
		(fp_line
			(start -0.7874 0.4064)
			(end -0.7874 -0.4064)
			(stroke
				(width 0.1524)
				(type default)
			)
			(layer "F.SilkS")
		)
		(fp_line
			(start 0.7874 0.4064)
			(end -0.7874 0.4064)
			(stroke
				(width 0.1524)
				(type default)
			)
			(layer "F.SilkS")
		)
		(fp_line
			(start -0.7874 -0.4064)
			(end 0.7874 -0.4064)
			(stroke
				(width 0.1524)
				(type default)
			)
			(layer "F.SilkS")
		)
		(fp_line
			(start 0.7874 -0.4064)
			(end 0.7874 0.4064)
			(stroke
				(width 0.1524)
				(type default)
			)
			(layer "F.SilkS")
		)
		(fp_line
			(start -0.67945 0.3048)
			(end -0.67945 -0.305054)
			(stroke
				(width 0.1)
				(type default)
			)
			(layer "F.Fab")
		)
		(fp_line
			(start -0.12065 0.3048)
			(end -0.67945 0.3048)
			(stroke
				(width 0.1)
				(type default)
			)
			(layer "F.Fab")
		)
		(fp_line
			(start 0.120396 0.3048)
			(end 0.120396 0.2794)
			(stroke
				(width 0.1)
				(type default)
			)
			(layer "F.Fab")
		)
		(fp_line
			(start 0.67945 0.3048)
			(end 0.120396 0.3048)
			(stroke
				(width 0.1)
				(type default)
			)
			(layer "F.Fab")
		)
		(fp_line
			(start -0.12065 0.2794)
			(end -0.12065 0.3048)
			(stroke
				(width 0.1)
				(type default)
			)
			(layer "F.Fab")
		)
		(fp_line
			(start 0.120396 0.2794)
			(end -0.12065 0.2794)
			(stroke
				(width 0.1)
				(type default)
			)
			(layer "F.Fab")
		)
		(fp_line
			(start -0.12065 -0.2794)
			(end 0.12065 -0.2794)
			(stroke
				(width 0.1)
				(type default)
			)
			(layer "F.Fab")
		)
		(fp_line
			(start 0.12065 -0.2794)
			(end 0.12065 -0.3048)
			(stroke
				(width 0.1)
				(type default)
			)
			(layer "F.Fab")
		)
		(fp_line
			(start 0.12065 -0.3048)
			(end 0.67945 -0.3048)
			(stroke
				(width 0.1)
				(type default)
			)
			(layer "F.Fab")
		)
		(fp_line
			(start 0.67945 -0.3048)
			(end 0.67945 0.3048)
			(stroke
				(width 0.1)
				(type default)
			)
			(layer "F.Fab")
		)
		(fp_line
			(start -0.67945 -0.305054)
			(end -0.12065 -0.305054)
			(stroke
				(width 0.1)
				(type default)
			)
			(layer "F.Fab")
		)
		(fp_line
			(start -0.12065 -0.305054)
			(end -0.12065 -0.2794)
			(stroke
				(width 0.1)
				(type default)
			)
			(layer "F.Fab")
		)
		(pad "1" smd circle
			(at -0.40005 0 270)
			(size 0 0)
			(layers "F.Cu" "F.Mask" "F.Paste")
			(net "BIC_UART_BMC_SEL_R")
		)
		(pad "2" smd circle
			(at 0.40005 0 270)
			(size 0 0)
			(layers "F.Cu" "F.Mask" "F.Paste")
			(net "BIC_UART_BMC_SEL")
		)
	)
	(footprint ""
		(layer "F.Cu")
		(at 211.435442 -244.016276 90)
		(property "Reference" "R1536"
			(at 0 0 90)
			(layer "F.SilkS")
			(hide yes)
			(effects
				(font
					(size 1.27 1.27)
				)
			)
		)
		(property "Value" ""
			(at 0 0 90)
			(layer "F.Fab")
			(effects
				(font
					(size 1.27 1.27)
				)
			)
		)
		(duplicate_pad_numbers_are_jumpers no)
		(fp_line
			(start 0.7874 -0.4064)
			(end 0.7874 0.4064)
			(stroke
				(width 0.1524)
				(type default)
			)
			(layer "F.SilkS")
		)
		(fp_line
			(start -0.7874 -0.4064)
			(end 0.7874 -0.4064)
			(stroke
				(width 0.1524)
				(type default)
			)
			(layer "F.SilkS")
		)
		(fp_line
			(start 0.7874 0.4064)
			(end -0.7874 0.4064)
			(stroke
				(width 0.1524)
				(type default)
			)
			(layer "F.SilkS")
		)
		(fp_line
			(start -0.7874 0.4064)
			(end -0.7874 -0.4064)
			(stroke
				(width 0.1524)
				(type default)
			)
			(layer "F.SilkS")
		)
		(fp_line
			(start -0.12065 -0.305054)
			(end -0.12065 -0.2794)
			(stroke
				(width 0.1)
				(type default)
			)
			(layer "F.Fab")
		)
		(fp_line
			(start -0.67945 -0.305054)
			(end -0.12065 -0.305054)
			(stroke
				(width 0.1)
				(type default)
			)
			(layer "F.Fab")
		)
		(fp_line
			(start 0.67945 -0.3048)
			(end 0.67945 0.3048)
			(stroke
				(width 0.1)
				(type default)
			)
			(layer "F.Fab")
		)
		(fp_line
			(start 0.12065 -0.3048)
			(end 0.67945 -0.3048)
			(stroke
				(width 0.1)
				(type default)
			)
			(layer "F.Fab")
		)
		(fp_line
			(start 0.12065 -0.2794)
			(end 0.12065 -0.3048)
			(stroke
				(width 0.1)
				(type default)
			)
			(layer "F.Fab")
		)
		(fp_line
			(start -0.12065 -0.2794)
			(end 0.12065 -0.2794)
			(stroke
				(width 0.1)
				(type default)
			)
			(layer "F.Fab")
		)
		(fp_line
			(start 0.120396 0.2794)
			(end -0.12065 0.2794)
			(stroke
				(width 0.1)
				(type default)
			)
			(layer "F.Fab")
		)
		(fp_line
			(start -0.12065 0.2794)
			(end -0.12065 0.3048)
			(stroke
				(width 0.1)
				(type default)
			)
			(layer "F.Fab")
		)
		(fp_line
			(start 0.67945 0.3048)
			(end 0.120396 0.3048)
			(stroke
				(width 0.1)
				(type default)
			)
			(layer "F.Fab")
		)
		(fp_line
			(start 0.120396 0.3048)
			(end 0.120396 0.2794)
			(stroke
				(width 0.1)
				(type default)
			)
			(layer "F.Fab")
		)
		(fp_line
			(start -0.12065 0.3048)
			(end -0.67945 0.3048)
			(stroke
				(width 0.1)
				(type default)
			)
			(layer "F.Fab")
		)
		(fp_line
			(start -0.67945 0.3048)
			(end -0.67945 -0.305054)
			(stroke
				(width 0.1)
				(type default)
			)
			(layer "F.Fab")
		)
		(pad "1" smd circle
			(at -0.40005 0 90)
			(size 0 0)
			(layers "F.Cu" "F.Mask" "F.Paste")
			(net "SMB_PEX_R_SCL")
		)
		(pad "2" smd circle
			(at 0.40005 0 90)
			(size 0 0)
			(layers "F.Cu" "F.Mask" "F.Paste")
			(net "P3V3_AUX")
		)
	)
	(footprint ""
		(layer "F.Cu")
		(at 454.125838 -312.439558 180)
		(property "Reference" "PC268"
			(at 0 0 180)
			(layer "F.SilkS")
			(hide yes)
			(effects
				(font
					(size 1.27 1.27)
				)
			)
		)
		(property "Value" ""
			(at 0 0 180)
			(layer "F.Fab")
			(effects
				(font
					(size 1.27 1.27)
				)
			)
		)
		(duplicate_pad_numbers_are_jumpers no)
		(fp_line
			(start 1.524 0.762)
			(end -1.524 0.762)
			(stroke
				(width 0.1524)
				(type default)
			)
			(layer "F.SilkS")
		)
		(fp_line
			(start 1.524 -0.762)
			(end 1.524 0.762)
			(stroke
				(width 0.1524)
				(type default)
			)
			(layer "F.SilkS")
		)
		(fp_line
			(start -1.524 0.762)
			(end -1.524 -0.762)
			(stroke
				(width 0.1524)
				(type default)
			)
			(layer "F.SilkS")
		)
		(fp_line
			(start -1.524 -0.762)
			(end 1.524 -0.762)
			(stroke
				(width 0.1524)
				(type default)
			)
			(layer "F.SilkS")
		)
		(fp_line
			(start 1.1049 0.724916)
			(end 1.1049 -0.724916)
			(stroke
				(width 0.1)
				(type default)
			)
			(layer "F.Fab")
		)
		(fp_line
			(start 1.1049 -0.724916)
			(end -1.1049 -0.724916)
			(stroke
				(width 0.1)
				(type default)
			)
			(layer "F.Fab")
		)
		(fp_line
			(start -1.1049 0.724916)
			(end 1.1049 0.724916)
			(stroke
				(width 0.1)
				(type default)
			)
			(layer "F.Fab")
		)
		(fp_line
			(start -1.1049 -0.724916)
			(end -1.1049 0.724916)
			(stroke
				(width 0.1)
				(type default)
			)
			(layer "F.Fab")
		)
		(pad "1" smd rect
			(at -0.889 0)
			(size 1.016 1.27)
			(layers "F.Cu" "F.Mask" "F.Paste")
			(net "SW_P12V_P1V25_PEX3_FLT")
		)
		(pad "2" smd rect
			(at 0.889 0)
			(size 1.016 1.27)
			(layers "F.Cu" "F.Mask" "F.Paste")
			(net "GND")
		)
	)
	(footprint ""
		(layer "F.Cu")
		(at 154.860244 -96.1644)
		(property "Reference" "R144"
			(at 0 0 0)
			(layer "F.SilkS")
			(hide yes)
			(effects
				(font
					(size 1.27 1.27)
				)
			)
		)
		(property "Value" ""
			(at 0 0 0)
			(layer "F.Fab")
			(effects
				(font
					(size 1.27 1.27)
				)
			)
		)
		(duplicate_pad_numbers_are_jumpers no)
		(fp_line
			(start -0.7874 -0.4064)
			(end 0.7874 -0.4064)
			(stroke
				(width 0.1524)
				(type default)
			)
			(layer "F.SilkS")
		)
		(fp_line
			(start -0.7874 0.4064)
			(end -0.7874 -0.4064)
			(stroke
				(width 0.1524)
				(type default)
			)
			(layer "F.SilkS")
		)
		(fp_line
			(start 0.7874 -0.4064)
			(end 0.7874 0.4064)
			(stroke
				(width 0.1524)
				(type default)
			)
			(layer "F.SilkS")
		)
		(fp_line
			(start 0.7874 0.4064)
			(end -0.7874 0.4064)
			(stroke
				(width 0.1524)
				(type default)
			)
			(layer "F.SilkS")
		)
		(fp_line
			(start -0.67945 -0.305054)
			(end -0.12065 -0.305054)
			(stroke
				(width 0.1)
				(type default)
			)
			(layer "F.Fab")
		)
		(fp_line
			(start -0.67945 0.3048)
			(end -0.67945 -0.305054)
			(stroke
				(width 0.1)
				(type default)
			)
			(layer "F.Fab")
		)
		(fp_line
			(start -0.12065 -0.305054)
			(end -0.12065 -0.2794)
			(stroke
				(width 0.1)
				(type default)
			)
			(layer "F.Fab")
		)
		(fp_line
			(start -0.12065 -0.2794)
			(end 0.12065 -0.2794)
			(stroke
				(width 0.1)
				(type default)
			)
			(layer "F.Fab")
		)
		(fp_line
			(start -0.12065 0.2794)
			(end -0.12065 0.3048)
			(stroke
				(width 0.1)
				(type default)
			)
			(layer "F.Fab")
		)
		(fp_line
			(start -0.12065 0.3048)
			(end -0.67945 0.3048)
			(stroke
				(width 0.1)
				(type default)
			)
			(layer "F.Fab")
		)
		(fp_line
			(start 0.120396 0.2794)
			(end -0.12065 0.2794)
			(stroke
				(width 0.1)
				(type default)
			)
			(layer "F.Fab")
		)
		(fp_line
			(start 0.120396 0.3048)
			(end 0.120396 0.2794)
			(stroke
				(width 0.1)
				(type default)
			)
			(layer "F.Fab")
		)
		(fp_line
			(start 0.12065 -0.3048)
			(end 0.67945 -0.3048)
			(stroke
				(width 0.1)
				(type default)
			)
			(layer "F.Fab")
		)
		(fp_line
			(start 0.12065 -0.2794)
			(end 0.12065 -0.3048)
			(stroke
				(width 0.1)
				(type default)
			)
			(layer "F.Fab")
		)
		(fp_line
			(start 0.67945 -0.3048)
			(end 0.67945 0.3048)
			(stroke
				(width 0.1)
				(type default)
			)
			(layer "F.Fab")
		)
		(fp_line
			(start 0.67945 0.3048)
			(end 0.120396 0.3048)
			(stroke
				(width 0.1)
				(type default)
			)
			(layer "F.Fab")
		)
		(pad "1" smd circle
			(at -0.40005 0)
			(size 0 0)
			(layers "F.Cu" "F.Mask" "F.Paste")
			(net "PRSNT_NIC2_N")
		)
		(pad "2" smd circle
			(at 0.40005 0)
			(size 0 0)
			(layers "F.Cu" "F.Mask" "F.Paste")
			(net "PRSNTB3_NIC2_N")
		)
	)
	(footprint ""
		(layer "F.Cu")
		(at 210.53552 -220.691456 -90)
		(property "Reference" "R2740"
			(at 0 0 270)
			(layer "F.SilkS")
			(hide yes)
			(effects
				(font
					(size 1.27 1.27)
				)
			)
		)
		(property "Value" ""
			(at 0 0 270)
			(layer "F.Fab")
			(effects
				(font
					(size 1.27 1.27)
				)
			)
		)
		(duplicate_pad_numbers_are_jumpers no)
		(fp_line
			(start -0.7874 0.4064)
			(end -0.7874 -0.4064)
			(stroke
				(width 0.1524)
				(type default)
			)
			(layer "F.SilkS")
		)
		(fp_line
			(start 0.7874 0.4064)
			(end -0.7874 0.4064)
			(stroke
				(width 0.1524)
				(type default)
			)
			(layer "F.SilkS")
		)
		(fp_line
			(start -0.7874 -0.4064)
			(end 0.7874 -0.4064)
			(stroke
				(width 0.1524)
				(type default)
			)
			(layer "F.SilkS")
		)
		(fp_line
			(start 0.7874 -0.4064)
			(end 0.7874 0.4064)
			(stroke
				(width 0.1524)
				(type default)
			)
			(layer "F.SilkS")
		)
		(fp_line
			(start -0.67945 0.3048)
			(end -0.67945 -0.305054)
			(stroke
				(width 0.1)
				(type default)
			)
			(layer "F.Fab")
		)
		(fp_line
			(start -0.12065 0.3048)
			(end -0.67945 0.3048)
			(stroke
				(width 0.1)
				(type default)
			)
			(layer "F.Fab")
		)
		(fp_line
			(start 0.120396 0.3048)
			(end 0.120396 0.2794)
			(stroke
				(width 0.1)
				(type default)
			)
			(layer "F.Fab")
		)
		(fp_line
			(start 0.67945 0.3048)
			(end 0.120396 0.3048)
			(stroke
				(width 0.1)
				(type default)
			)
			(layer "F.Fab")
		)
		(fp_line
			(start -0.12065 0.2794)
			(end -0.12065 0.3048)
			(stroke
				(width 0.1)
				(type default)
			)
			(layer "F.Fab")
		)
		(fp_line
			(start 0.120396 0.2794)
			(end -0.12065 0.2794)
			(stroke
				(width 0.1)
				(type default)
			)
			(layer "F.Fab")
		)
		(fp_line
			(start -0.12065 -0.2794)
			(end 0.12065 -0.2794)
			(stroke
				(width 0.1)
				(type default)
			)
			(layer "F.Fab")
		)
		(fp_line
			(start 0.12065 -0.2794)
			(end 0.12065 -0.3048)
			(stroke
				(width 0.1)
				(type default)
			)
			(layer "F.Fab")
		)
		(fp_line
			(start 0.12065 -0.3048)
			(end 0.67945 -0.3048)
			(stroke
				(width 0.1)
				(type default)
			)
			(layer "F.Fab")
		)
		(fp_line
			(start 0.67945 -0.3048)
			(end 0.67945 0.3048)
			(stroke
				(width 0.1)
				(type default)
			)
			(layer "F.Fab")
		)
		(fp_line
			(start -0.67945 -0.305054)
			(end -0.12065 -0.305054)
			(stroke
				(width 0.1)
				(type default)
			)
			(layer "F.Fab")
		)
		(fp_line
			(start -0.12065 -0.305054)
			(end -0.12065 -0.2794)
			(stroke
				(width 0.1)
				(type default)
			)
			(layer "F.Fab")
		)
		(pad "1" smd circle
			(at -0.40005 0 270)
			(size 0 0)
			(layers "F.Cu" "F.Mask" "F.Paste")
			(net "BUF_UART_MB_BIC_TX_EN")
		)
		(pad "2" smd circle
			(at 0.40005 0 270)
			(size 0 0)
			(layers "F.Cu" "F.Mask" "F.Paste")
			(net "P3V3_AUX")
		)
	)
	(footprint ""
		(layer "F.Cu")
		(at 115.64239 -258.14655 180)
		(property "Reference" "PR94"
			(at 0 0 180)
			(layer "F.SilkS")
			(hide yes)
			(effects
				(font
					(size 1.27 1.27)
				)
			)
		)
		(property "Value" ""
			(at 0 0 180)
			(layer "F.Fab")
			(effects
				(font
					(size 1.27 1.27)
				)
			)
		)
		(duplicate_pad_numbers_are_jumpers no)
		(fp_line
			(start 0.7874 0.4064)
			(end -0.7874 0.4064)
			(stroke
				(width 0.1524)
				(type default)
			)
			(layer "F.SilkS")
		)
		(fp_line
			(start 0.7874 -0.4064)
			(end 0.7874 0.4064)
			(stroke
				(width 0.1524)
				(type default)
			)
			(layer "F.SilkS")
		)
		(fp_line
			(start -0.7874 0.4064)
			(end -0.7874 -0.4064)
			(stroke
				(width 0.1524)
				(type default)
			)
			(layer "F.SilkS")
		)
		(fp_line
			(start -0.7874 -0.4064)
			(end 0.7874 -0.4064)
			(stroke
				(width 0.1524)
				(type default)
			)
			(layer "F.SilkS")
		)
		(fp_line
			(start 0.67945 0.3048)
			(end 0.120396 0.3048)
			(stroke
				(width 0.1)
				(type default)
			)
			(layer "F.Fab")
		)
		(fp_line
			(start 0.67945 -0.3048)
			(end 0.67945 0.3048)
			(stroke
				(width 0.1)
				(type default)
			)
			(layer "F.Fab")
		)
		(fp_line
			(start 0.12065 -0.2794)
			(end 0.12065 -0.3048)
			(stroke
				(width 0.1)
				(type default)
			)
			(layer "F.Fab")
		)
		(fp_line
			(start 0.12065 -0.3048)
			(end 0.67945 -0.3048)
			(stroke
				(width 0.1)
				(type default)
			)
			(layer "F.Fab")
		)
		(fp_line
			(start 0.120396 0.3048)
			(end 0.120396 0.2794)
			(stroke
				(width 0.1)
				(type default)
			)
			(layer "F.Fab")
		)
		(fp_line
			(start 0.120396 0.2794)
			(end -0.12065 0.2794)
			(stroke
				(width 0.1)
				(type default)
			)
			(layer "F.Fab")
		)
		(fp_line
			(start -0.12065 0.3048)
			(end -0.67945 0.3048)
			(stroke
				(width 0.1)
				(type default)
			)
			(layer "F.Fab")
		)
		(fp_line
			(start -0.12065 0.2794)
			(end -0.12065 0.3048)
			(stroke
				(width 0.1)
				(type default)
			)
			(layer "F.Fab")
		)
		(fp_line
			(start -0.12065 -0.2794)
			(end 0.12065 -0.2794)
			(stroke
				(width 0.1)
				(type default)
			)
			(layer "F.Fab")
		)
		(fp_line
			(start -0.12065 -0.305054)
			(end -0.12065 -0.2794)
			(stroke
				(width 0.1)
				(type default)
			)
			(layer "F.Fab")
		)
		(fp_line
			(start -0.67945 0.3048)
			(end -0.67945 -0.305054)
			(stroke
				(width 0.1)
				(type default)
			)
			(layer "F.Fab")
		)
		(fp_line
			(start -0.67945 -0.305054)
			(end -0.12065 -0.305054)
			(stroke
				(width 0.1)
				(type default)
			)
			(layer "F.Fab")
		)
		(pad "1" smd circle
			(at -0.40005 0 180)
			(size 0 0)
			(layers "F.Cu" "F.Mask" "F.Paste")
			(net "P0V8_PEX0_IINSEN")
		)
		(pad "2" smd circle
			(at 0.40005 0 180)
			(size 0 0)
			(layers "F.Cu" "F.Mask" "F.Paste")
			(net "GND")
		)
	)
)
